# BASEBOARD_FAB2 (Tioga Pass) — schematic netlist excerpt (pin names and nets, part order shuffled) for the footprints in the layout excerpt that follows; sources: Cadence DE-HDL packaged netlist, KiCad conversion of Wiwynn_Tioga_Pass_MB.brd

R3N24  RES  33.2 1% CHIP  pkg 0402  page 146 : A = LPC_LAD2_IO2 ; B = LPC_LAD2_IO2_R
R1D37  RES  100.0K 1% CHIP  pkg 0402  page 199 : A = A_HSC_VCAP ; B = A_HSC_ISET

(kicad_pcb
	(version 20260206)
	(generator "pcbnew")
	(generator_version "10.0")
	(general
		(thickness 1.6)
		(legacy_teardrops no)
	)
	(paper "A4")
	(title_block
		(title "Wiwynn_Tioga_Pass_MB.brd")
		(comment 1 "Tioga Pass / footprints 212-213 of 4770")
	)
	(layers
		(0 "F.Cu" signal "TOP")
		(4 "In1.Cu" signal "L2GND")
		(6 "In2.Cu" signal "L3")
		(8 "In3.Cu" signal "L4GND")
		(10 "In4.Cu" signal "L5")
		(12 "In5.Cu" signal "L6GND")
		(14 "In6.Cu" signal "L7VCC")
		(16 "In7.Cu" signal "L8VCC")
		(18 "In8.Cu" signal "L9GND")
		(20 "In9.Cu" signal "L10")
		(22 "In10.Cu" signal "L11GND")
		(24 "In11.Cu" signal "L12")
		(26 "In12.Cu" signal "L13GND")
		(2 "B.Cu" signal "BOTTOM")
		(9 "F.Adhes" user "F.Adhesive")
		(11 "B.Adhes" user "B.Adhesive")
		(13 "F.Paste" user "Package Geometry/Pastemask Top")
		(15 "B.Paste" user "Package Geometry/Pastemask Bottom")
		(5 "F.SilkS" user "Ref Des/Silkscreen Top")
		(7 "B.SilkS" user "Ref Des/Silkscreen Bottom")
		(1 "F.Mask" user "Board Geometry/Soldermask Top")
		(3 "B.Mask" user "Board Geometry/Soldermask Bottom")
		(17 "Dwgs.User" user "User.Drawings")
		(19 "Cmts.User" user "User.Comments")
		(21 "Eco1.User" user "User.Eco1")
		(23 "Eco2.User" user "User.Eco2")
		(25 "Edge.Cuts" user "Board Geometry/Outline")
		(27 "Margin" user)
		(31 "F.CrtYd" user "Package Geometry/Place Bound Top")
		(29 "B.CrtYd" user "Package Geometry/Place Bound Bottom")
		(35 "F.Fab" user "Ref Des/Assembly Top")
		(33 "B.Fab" user "Ref Des/Assembly Bottom")
	)
	(footprint ""
		(layer "F.Cu")
		(at 23.114 -74.549 -90)
		(property "Reference" "R1D37"
			(at 0 0 270)
			(layer "F.SilkS")
			(hide yes)
			(effects
				(font
					(size 1.27 1.27)
				)
			)
		)
		(property "Value" ""
			(at 0 0 270)
			(layer "F.Fab")
			(effects
				(font
					(size 1.27 1.27)
				)
			)
		)
		(duplicate_pad_numbers_are_jumpers no)
		(fp_poly
			(pts
				(xy -0.2794 -0.1016) (xy 0.2794 -0.1016) (xy 0.2794 0.9906) (xy -0.2794 0.9906)
			)
			(stroke
				(width 0)
				(type default)
			)
			(fill no)
			(layer "F.CrtYd")
		)
		(fp_line
			(start -0.2794 0.9906)
			(end 0.2794 0.9906)
			(stroke
				(width 0.1)
				(type default)
			)
			(layer "F.Fab")
		)
		(fp_line
			(start 0.2794 0.9906)
			(end 0.2794 -0.1016)
			(stroke
				(width 0.1)
				(type default)
			)
			(layer "F.Fab")
		)
		(fp_line
			(start -0.2794 -0.1016)
			(end -0.2794 0.9906)
			(stroke
				(width 0.1)
				(type default)
			)
			(layer "F.Fab")
		)
		(fp_line
			(start 0.2794 -0.1016)
			(end -0.2794 -0.1016)
			(stroke
				(width 0.1)
				(type default)
			)
			(layer "F.Fab")
		)
		(pad "1" smd rect
			(at 0 0 270)
			(size 0.508 0.508)
			(layers "F.Cu" "F.Mask" "F.Paste")
			(net "A_HSC_VCAP")
		)
		(pad "2" smd rect
			(at 0 0.889 270)
			(size 0.508 0.508)
			(layers "F.Cu" "F.Mask" "F.Paste")
			(net "A_HSC_ISET")
		)
		(zone
			(layer "F.Cu")
			(hatch none 0.5)
			(connect_pads
				(clearance 0)
			)
			(min_thickness 0.25)
			(keepout
				(tracks not_allowed)
				(vias allowed)
				(pads allowed)
				(copperpour not_allowed)
				(footprints allowed)
			)
			(placement
				(enabled no)
				(sheetname "")
			)
			(fill
				(thermal_gap 0.5)
				(thermal_bridge_width 0.5)
				(island_removal_mode 0)
			)
			(polygon
				(pts
					(xy 22.479 -74.803) (xy 22.479 -74.295) (xy 22.86 -74.295) (xy 22.86 -74.803)
				)
			)
		)
		(zone
			(layer "F.Cu")
			(hatch none 0.5)
			(connect_pads
				(clearance 0)
			)
			(min_thickness 0.25)
			(keepout
				(tracks allowed)
				(vias not_allowed)
				(pads allowed)
				(copperpour not_allowed)
				(footprints allowed)
			)
			(placement
				(enabled no)
				(sheetname "")
			)
			(fill
				(thermal_gap 0.5)
				(thermal_bridge_width 0.5)
				(island_removal_mode 0)
			)
			(polygon
				(pts
					(xy 22.86 -74.803) (xy 22.86 -74.295) (xy 22.479 -74.295) (xy 22.479 -74.803)
				)
			)
		)
	)
	(footprint ""
		(layer "F.Cu")
		(at 379.984 -88.2015)
		(property "Reference" "R3N24"
			(at 0 0 0)
			(layer "F.SilkS")
			(hide yes)
			(effects
				(font
					(size 1.27 1.27)
				)
			)
		)
		(property "Value" ""
			(at 0 0 0)
			(layer "F.Fab")
			(effects
				(font
					(size 1.27 1.27)
				)
			)
		)
		(duplicate_pad_numbers_are_jumpers no)
		(fp_poly
			(pts
				(xy -0.2794 -0.1016) (xy 0.2794 -0.1016) (xy 0.2794 0.9906) (xy -0.2794 0.9906)
			)
			(stroke
				(width 0)
				(type default)
			)
			(fill no)
			(layer "F.CrtYd")
		)
		(fp_line
			(start -0.2794 -0.1016)
			(end -0.2794 0.9906)
			(stroke
				(width 0.1)
				(type default)
			)
			(layer "F.Fab")
		)
		(fp_line
			(start -0.2794 0.9906)
			(end 0.2794 0.9906)
			(stroke
				(width 0.1)
				(type default)
			)
			(layer "F.Fab")
		)
		(fp_line
			(start 0.2794 -0.1016)
			(end -0.2794 -0.1016)
			(stroke
				(width 0.1)
				(type default)
			)
			(layer "F.Fab")
		)
		(fp_line
			(start 0.2794 0.9906)
			(end 0.2794 -0.1016)
			(stroke
				(width 0.1)
				(type default)
			)
			(layer "F.Fab")
		)
		(pad "1" smd rect
			(at 0 0)
			(size 0.508 0.508)
			(layers "F.Cu" "F.Mask" "F.Paste")
			(net "LPC_LAD2_IO2")
		)
		(pad "2" smd rect
			(at 0 0.889)
			(size 0.508 0.508)
			(layers "F.Cu" "F.Mask" "F.Paste")
			(net "LPC_LAD2_IO2_R")
		)
		(zone
			(layer "F.Cu")
			(hatch none 0.5)
			(connect_pads
				(clearance 0)
			)
			(min_thickness 0.25)
			(keepout
				(tracks allowed)
				(vias not_allowed)
				(pads allowed)
				(copperpour not_allowed)
				(footprints allowed)
			)
			(placement
				(enabled no)
				(sheetname "")
			)
			(fill
				(thermal_gap 0.5)
				(thermal_bridge_width 0.5)
				(island_removal_mode 0)
			)
			(polygon
				(pts
					(xy 379.73 -87.9475) (xy 380.238 -87.9475) (xy 380.238 -87.5665) (xy 379.73 -87.5665)
				)
			)
		)
		(zone
			(layer "F.Cu")
			(hatch none 0.5)
			(connect_pads
				(clearance 0)
			)
			(min_thickness 0.25)
			(keepout
				(tracks not_allowed)
				(vias allowed)
				(pads allowed)
				(copperpour not_allowed)
				(footprints allowed)
			)
			(placement
				(enabled no)
				(sheetname "")
			)
			(fill
				(thermal_gap 0.5)
				(thermal_bridge_width 0.5)
				(island_removal_mode 0)
			)
			(polygon
				(pts
					(xy 379.73 -87.5665) (xy 380.238 -87.5665) (xy 380.238 -87.9475) (xy 379.73 -87.9475)
				)
			)
		)
	)
)
